# BARRELEYE_G2-FPDB_POST-PVT-X02-BOM-X05-20171123_Final.xls.xlsx — Single-Sole Source Parts List (bom)
| FOXCONN TECHNOLOGY GROUP |  |  |  |  |  |  |  |  |  |  |  |  |  |  |  |  |  |
| BILL OF MATERIAL |  |  |  |  |  |  |  |  |  |  |  |  |  |  |  |  |  |
| REV OF  BOM | X05 | CUSTOMER | <name> |  | CUSTOMER P/N |  | PWA P/N： | PWA DESCRIPTION |  |  | PRODUCT CODE |  |  | PWA REV | X02 | DATE | 43060 |
| Sourcing (Single or Sole | Critical Commodity (Y or N) | Component Class (1, 2, other) | Customer PSL (Y/N) | Item Number | Foxconn P/N | Customer P/N | Part Description | Mfr. 1 | Mfr Part # 1 | Proposed Mfr. 2 | Proposed Mfr. 2 PN | Qty | RoHS Status | Location | 2nd Source Qual Build: | Customer Comments | ODM Comments |
|  |  |  |  | 18 | 730101C00-086-G |  | Fuse,Slow blow,125V,30A,G,SMD | LITTELFUSE FAR EAST PTE LTD | 0456030.ER |  |  | 3 | G | FS1,FS2,FS10 |  |  |  |
|  |  |  |  | 25 | 62012T500-015-G |  | CAP,22uF,+/-20%,X7S,25V,G,SMD1206 | MURATA ELEC. NORTH AMERICA | GRM31CC71E226ME11L |  |  | 14 | G | PSRC2,PSUC5,PEUC5,PSUC6,PEUC6,PSUC7,PEUC7,PSUC8,PEUC8,PSUC9,PEUC9,PSUC10,PEUC10,PSRC17 |  |  |  |
|  |  |  |  | 35 | 52030YE00-223-G |  | DIODE,Schottky,MBR5H100MFST1G,100V,5A,G,SO8FL-8,SMD | ON SEMICONDUCTOR CORP | MBR5H100MFST1G |  |  | 1 | G | PHAD2 |  |  |  |
|  |  |  |  | 39 | 51032D100-237-G |  | MOS N,DMN10H220L-7,100V,1.6A,220m@10V,G,SOT-23-3,SMD | DIODES INCORPORATION | DMN10H220L-7 |  |  | 2 | G | PHAQ5,PHAQ9 |  |  |  |
|  |  |  |  | 41 | 610601800-32D-G |  | RES,0.5mOhm,+/-1%,2W,G,SMD1225 | Thin Film Technology Corporation | CPA1225R0M50FW-T50 |  |  | 1 | G | PHAR1 |  |  |  |
|  |  |  |  | 54 | 32023RR00-183-G |  | IC,Power Controller,LM5066IPMHX/NOPB,G,HTSSOP-28,SMD | TEXAS INSTRUMENTS | LM5066IPMHX/NOPB |  |  | 1 | G | PHAU1 |  |  |  |
|  |  |  |  | 68 | 32013PD00-238-G |  | IC,Regulator,IR3883MTRPbF,ADJ,3A,G,QFN-16,SMD | INTERNATIONAL RECTIFIER | IR3883MTRPBF |  |  | 1 | G | PSRU1 |  |  |  |
|  |  |  |  | 73 | 51040EK00-185-G |  | MOS P,FDMS6681Z,30V,49A,5m@4.5V,G,Power56-8,SMD | FAIRCHILD SEMICONDUCTOR CORP | FDMS6681Z |  |  | 2 | G | Q13,Q14 |  |  |  |
|  |  |  |  | 102 | 310204100-183-G | - | IC,Gate&Inverter,SN74LVC1G14DCKR,1.65~5.5V,G,SC70-5,SMD | TEXAS INSTRUMENTS | SN74LVC1G14DCKR |  |  | 1 | G | U2 |  |  |  |
|  |  |  |  | 103 | 32040QL00-09N-G |  | IC,Temp Sensor,A,NCT7904D,N/A,G,LQFP-48,SMD | Nuvoton Technology Corporation | NCT7904D |  |  | 2 | G | U3,U4 |  |  |  |
|  |  |  |  | 104 | 31010DT00-031-G |  | IC,Gate,74LVC1G02GW,1.65~5.5V,G,SC88A-5,SMD | NXP SEMICONDUCTORS | 74LVC1G02GW |  |  | 1 | G | U5 |  |  |  |
|  |  |  |  | 106 | 31010SB00-183-G |  | Logic IC,Gate,ISO1540DR,3V~5.5V,G,SOIC-8,SMD | TEXAS INSTRUMENTS | ISO1540DR |  |  | 1 | G | U7 |  |  |  |
|  |  |  |  | 107 | 310500U00-183-G | - | IC,Buffer,SN74LVC07APWR,1.65~5V,G,TSSOP-14,SMD | TEXAS INSTRUMENTS | SN74LVC07APWR |  |  | 1 | G | U15 |  |  |  |
|  |  |  |  | 108 | 320306E00-183-G |  | IC,Comparator,LMV331IDBVR,9mV,G,SOT23-5,SMD | TEXAS INSTRUMENTS | LMV331IDBVR |  |  | 2 | G | U16,U17 |  |  |  |
|  |  |  |  | 109 | 210204300-031-G |  | IC,NXP,PCA9535PW,G,TSSOP-24,SMD | NXP SEMICONDUCTORS | PCA9535PW |  |  | 1 | G | U18 |  |  |  |
|  |  |  |  | 112 | 320242H00-226-G |  | IC,Power Controller,LTC2955CDDB-2#TRMPBF,G,DFN-10,SMD | LINEAR TECHNOLOGY CORPORATION | LTC2955CDDB-2#TRMPBF |  |  | 1 | G | U165 |  |  |  |
|  |  |  |  | 114 | 340636700-600-G |  | CONN,Header,Power,2X8,V/T,Whi,4.2mm,G,DIP-16 | FOXCONN TECHNOLOGY CO.,LTD. | HM3508E-HP1 |  |  | 1 | G | J_EXP_PWR1 |  |  |  |
|  |  |  |  | 115 | 340636800-600-G |  | CONN,Header,Power,2X9,V/T,Whi,4.2mm,G,DIP-18 | FOXCONN TECHNOLOGY CO.,LTD. | HM3509E-HP1 |  |  | 1 | G | J_GPU_PWR1 |  |  |  |
|  |  |  |  | 118 | 34044PP00-G78-G |  | CONN,I/O,Terminal Blocks,R/A,Bla,4mm,G,DIP-4 | FCI CONNECTORS HONGKONG LTD. | VP02650700J0G |  |  | 1 | G | J_TERMINAL_GND1 |  |  |  |
|  |  |  |  | 119 | 34044PQ00-G78-G |  | CONN,I/O,Terminal Blocks,R/A,Red,4mm,G,DIP-4 | FCI CONNECTORS HONGKONG LTD. | VP02652700J0G |  |  | 1 | G | J_TERMINAL_48V1 |  |  |  |
|  |  |  |  | 120 | 3406ANQ00-317-G |  | CONN,Header,Power,V/T,Bla,10mm,30u,G,DIP-8 | MOLEX INCORPORATED | 42819-4213 |  |  | 1 | G | J1 |  |  |  |
|  |  |  |  | 121 | 3406ALY00-317-G |  | CONN,Header,Shrouded,2X6,V/T,Bla,2mm,30u,G,SMD-12 | MOLEX INCORPORATED | 87832-5523 |  |  | 1 | G | J2 |  |  |  |
|  |  |  |  | 122 | 3406ALW00-317-G |  | CONN,Header,Shrouded,2X5,V/T,Bla,2mm,30u,G,SMD-10 | MOLEX INCORPORATED | 87832-5423 |  |  | 1 | G | J3 |  |  |  |
|  |  |  |  | 123 | 3406A1800-317-G |  | CONN,Header,WTB,1X8,V/T,Bla,2.54mm,G,DIP-8 | MOLEX INCORPORATED | 171856-0108 |  |  | 6 | G | J4,J5,J6,J7,J8,J9 |  |  |  |
